(kicad_pcb
	(version 20260206)
	(generator "pcbnew")
	(generator_version "10.0")
	(general
		(thickness 1.6)
		(legacy_teardrops no)
	)
	(paper "A4")
	(title_block
		(title "04192023_DAF0TMB3IC0_F0TG_MB_C_brd_V02_OCP.brd")
		(comment 1 "Grand Teton / footprints 4255-4261 of 8354")
	)
	(layers
		(0 "F.Cu" signal "TOP")
		(4 "In1.Cu" signal "GND")
		(6 "In2.Cu" signal "IN1")
		(8 "In3.Cu" signal "GND1")
		(10 "In4.Cu" signal "IN2")
		(12 "In5.Cu" signal "GND2")
		(14 "In6.Cu" signal "IN3")
		(16 "In7.Cu" signal "GND3")
		(18 "In8.Cu" signal "VCC")
		(20 "In9.Cu" signal "VCC1")
		(22 "In10.Cu" signal "GND4")
		(24 "In11.Cu" signal "IN4")
		(26 "In12.Cu" signal "GND5")
		(28 "In13.Cu" signal "IN5")
		(30 "In14.Cu" signal "GND6")
		(32 "In15.Cu" signal "IN6")
		(34 "In16.Cu" signal "GND7")
		(2 "B.Cu" signal "BOTTOM")
		(9 "F.Adhes" user "F.Adhesive")
		(11 "B.Adhes" user "B.Adhesive")
		(13 "F.Paste" user "Package Geometry/Pastemask Top")
		(15 "B.Paste" user "Package Geometry/Pastemask Bottom")
		(5 "F.SilkS" user "Ref Des/Silkscreen Top")
		(7 "B.SilkS" user "Ref Des/Silkscreen Bottom")
		(1 "F.Mask" user "Board Geometry/Soldermask Top")
		(3 "B.Mask" user "Board Geometry/Soldermask Bottom")
		(17 "Dwgs.User" user "User.Drawings")
		(19 "Cmts.User" user "User.Comments")
		(21 "Eco1.User" user "User.Eco1")
		(23 "Eco2.User" user "User.Eco2")
		(25 "Edge.Cuts" user "Board Geometry/Outline")
		(27 "Margin" user)
		(31 "F.CrtYd" user "Package Geometry/Place Bound Top")
		(29 "B.CrtYd" user "Package Geometry/Place Bound Bottom")
		(35 "F.Fab" user "Ref Des/Assembly Top")
		(33 "B.Fab" user "Ref Des/Assembly Bottom")
	)
	(footprint ""
		(layer "F.Cu")
		(at 102.357682 -394.697966 90)
		(property "Reference" "R6707"
			(at 0 0 90)
			(layer "F.SilkS")
			(hide yes)
			(effects
				(font
					(size 1.27 1.27)
				)
			)
		)
		(property "Value" ""
			(at 0 0 90)
			(layer "F.Fab")
			(effects
				(font
					(size 1.27 1.27)
				)
			)
		)
		(duplicate_pad_numbers_are_jumpers no)
		(fp_line
			(start 0.32512 -0.175006)
			(end 0.32512 0.175006)
			(stroke
				(width 0.1)
				(type default)
			)
			(layer "F.Fab")
		)
		(fp_line
			(start -0.32512 -0.175006)
			(end 0.32512 -0.175006)
			(stroke
				(width 0.1)
				(type default)
			)
			(layer "F.Fab")
		)
		(fp_line
			(start 0.32512 0.175006)
			(end -0.32512 0.175006)
			(stroke
				(width 0.1)
				(type default)
			)
			(layer "F.Fab")
		)
		(fp_line
			(start -0.32512 0.175006)
			(end -0.32512 -0.175006)
			(stroke
				(width 0.1)
				(type default)
			)
			(layer "F.Fab")
		)
		(pad "1" smd rect
			(at -0.2667 0 90)
			(size 0.3048 0.381)
			(layers "F.Cu" "F.Mask" "F.Paste")
			(net "P1V8_CPU1_RT_1D")
		)
		(pad "2" smd rect
			(at 0.2667 0 270)
			(size 0.3048 0.381)
			(layers "F.Cu" "F.Mask" "F.Paste")
			(net "SMB_RT_CPU1_P0_ROM_R_SDA")
		)
	)
	(footprint ""
		(layer "F.Cu")
		(at 102.563422 -38.678612 180)
		(property "Reference" "R3183"
			(at 0 0 180)
			(layer "F.SilkS")
			(hide yes)
			(effects
				(font
					(size 1.27 1.27)
				)
			)
		)
		(property "Value" ""
			(at 0 0 180)
			(layer "F.Fab")
			(effects
				(font
					(size 1.27 1.27)
				)
			)
		)
		(duplicate_pad_numbers_are_jumpers no)
		(fp_line
			(start 0.7874 0.4064)
			(end -0.7874 0.4064)
			(stroke
				(width 0.1524)
				(type default)
			)
			(layer "F.SilkS")
		)
		(fp_line
			(start 0.7874 -0.4064)
			(end 0.7874 0.4064)
			(stroke
				(width 0.1524)
				(type default)
			)
			(layer "F.SilkS")
		)
		(fp_line
			(start -0.7874 0.4064)
			(end -0.7874 -0.4064)
			(stroke
				(width 0.1524)
				(type default)
			)
			(layer "F.SilkS")
		)
		(fp_line
			(start -0.7874 -0.4064)
			(end 0.7874 -0.4064)
			(stroke
				(width 0.1524)
				(type default)
			)
			(layer "F.SilkS")
		)
		(fp_line
			(start 0.67945 0.3048)
			(end 0.120396 0.3048)
			(stroke
				(width 0.1)
				(type default)
			)
			(layer "F.Fab")
		)
		(fp_line
			(start 0.67945 -0.3048)
			(end 0.67945 0.3048)
			(stroke
				(width 0.1)
				(type default)
			)
			(layer "F.Fab")
		)
		(fp_line
			(start 0.12065 -0.2794)
			(end 0.12065 -0.3048)
			(stroke
				(width 0.1)
				(type default)
			)
			(layer "F.Fab")
		)
		(fp_line
			(start 0.12065 -0.3048)
			(end 0.67945 -0.3048)
			(stroke
				(width 0.1)
				(type default)
			)
			(layer "F.Fab")
		)
		(fp_line
			(start 0.120396 0.3048)
			(end 0.120396 0.2794)
			(stroke
				(width 0.1)
				(type default)
			)
			(layer "F.Fab")
		)
		(fp_line
			(start 0.120396 0.2794)
			(end -0.12065 0.2794)
			(stroke
				(width 0.1)
				(type default)
			)
			(layer "F.Fab")
		)
		(fp_line
			(start -0.12065 0.3048)
			(end -0.67945 0.3048)
			(stroke
				(width 0.1)
				(type default)
			)
			(layer "F.Fab")
		)
		(fp_line
			(start -0.12065 0.2794)
			(end -0.12065 0.3048)
			(stroke
				(width 0.1)
				(type default)
			)
			(layer "F.Fab")
		)
		(fp_line
			(start -0.12065 -0.2794)
			(end 0.12065 -0.2794)
			(stroke
				(width 0.1)
				(type default)
			)
			(layer "F.Fab")
		)
		(fp_line
			(start -0.12065 -0.305054)
			(end -0.12065 -0.2794)
			(stroke
				(width 0.1)
				(type default)
			)
			(layer "F.Fab")
		)
		(fp_line
			(start -0.67945 0.3048)
			(end -0.67945 -0.305054)
			(stroke
				(width 0.1)
				(type default)
			)
			(layer "F.Fab")
		)
		(fp_line
			(start -0.67945 -0.305054)
			(end -0.12065 -0.305054)
			(stroke
				(width 0.1)
				(type default)
			)
			(layer "F.Fab")
		)
		(pad "1" smd circle
			(at -0.40005 0 180)
			(size 0 0)
			(layers "F.Cu" "F.Mask" "F.Paste")
			(net "P3V3_OCP_V3_2")
		)
		(pad "2" smd circle
			(at 0.40005 0 180)
			(size 0 0)
			(layers "F.Cu" "F.Mask" "F.Paste")
			(net "PU_OCP_V3_2_WAKE_OE")
		)
	)
	(footprint ""
		(layer "F.Cu")
		(at 138.426952 -60.849764)
		(property "Reference" "R1738"
			(at 0 0 0)
			(layer "F.SilkS")
			(hide yes)
			(effects
				(font
					(size 1.27 1.27)
				)
			)
		)
		(property "Value" ""
			(at 0 0 0)
			(layer "F.Fab")
			(effects
				(font
					(size 1.27 1.27)
				)
			)
		)
		(duplicate_pad_numbers_are_jumpers no)
		(fp_line
			(start -0.7874 -0.4064)
			(end 0.7874 -0.4064)
			(stroke
				(width 0.1524)
				(type default)
			)
			(layer "F.SilkS")
		)
		(fp_line
			(start -0.7874 0.4064)
			(end -0.7874 -0.4064)
			(stroke
				(width 0.1524)
				(type default)
			)
			(layer "F.SilkS")
		)
		(fp_line
			(start 0.7874 -0.4064)
			(end 0.7874 0.4064)
			(stroke
				(width 0.1524)
				(type default)
			)
			(layer "F.SilkS")
		)
		(fp_line
			(start 0.7874 0.4064)
			(end -0.7874 0.4064)
			(stroke
				(width 0.1524)
				(type default)
			)
			(layer "F.SilkS")
		)
		(fp_line
			(start -0.67945 -0.305054)
			(end -0.12065 -0.305054)
			(stroke
				(width 0.1)
				(type default)
			)
			(layer "F.Fab")
		)
		(fp_line
			(start -0.67945 0.3048)
			(end -0.67945 -0.305054)
			(stroke
				(width 0.1)
				(type default)
			)
			(layer "F.Fab")
		)
		(fp_line
			(start -0.12065 -0.305054)
			(end -0.12065 -0.2794)
			(stroke
				(width 0.1)
				(type default)
			)
			(layer "F.Fab")
		)
		(fp_line
			(start -0.12065 -0.2794)
			(end 0.12065 -0.2794)
			(stroke
				(width 0.1)
				(type default)
			)
			(layer "F.Fab")
		)
		(fp_line
			(start -0.12065 0.2794)
			(end -0.12065 0.3048)
			(stroke
				(width 0.1)
				(type default)
			)
			(layer "F.Fab")
		)
		(fp_line
			(start -0.12065 0.3048)
			(end -0.67945 0.3048)
			(stroke
				(width 0.1)
				(type default)
			)
			(layer "F.Fab")
		)
		(fp_line
			(start 0.120396 0.2794)
			(end -0.12065 0.2794)
			(stroke
				(width 0.1)
				(type default)
			)
			(layer "F.Fab")
		)
		(fp_line
			(start 0.120396 0.3048)
			(end 0.120396 0.2794)
			(stroke
				(width 0.1)
				(type default)
			)
			(layer "F.Fab")
		)
		(fp_line
			(start 0.12065 -0.3048)
			(end 0.67945 -0.3048)
			(stroke
				(width 0.1)
				(type default)
			)
			(layer "F.Fab")
		)
		(fp_line
			(start 0.12065 -0.2794)
			(end 0.12065 -0.3048)
			(stroke
				(width 0.1)
				(type default)
			)
			(layer "F.Fab")
		)
		(fp_line
			(start 0.67945 -0.3048)
			(end 0.67945 0.3048)
			(stroke
				(width 0.1)
				(type default)
			)
			(layer "F.Fab")
		)
		(fp_line
			(start 0.67945 0.3048)
			(end 0.120396 0.3048)
			(stroke
				(width 0.1)
				(type default)
			)
			(layer "F.Fab")
		)
		(pad "1" smd circle
			(at -0.40005 0)
			(size 0 0)
			(layers "F.Cu" "F.Mask" "F.Paste")
			(net "JTAG_SCM_MUX_R_TDI")
		)
		(pad "2" smd circle
			(at 0.40005 0)
			(size 0 0)
			(layers "F.Cu" "F.Mask" "F.Paste")
			(net "JTAG_SCM_MUX_TDI")
		)
	)
	(footprint ""
		(layer "F.Cu")
		(at 156.718 -106.172 180)
		(property "Reference" "R1131"
			(at 0 0 180)
			(layer "F.SilkS")
			(hide yes)
			(effects
				(font
					(size 1.27 1.27)
				)
			)
		)
		(property "Value" ""
			(at 0 0 180)
			(layer "F.Fab")
			(effects
				(font
					(size 1.27 1.27)
				)
			)
		)
		(duplicate_pad_numbers_are_jumpers no)
		(fp_line
			(start 0.7874 0.4064)
			(end -0.7874 0.4064)
			(stroke
				(width 0.1524)
				(type default)
			)
			(layer "F.SilkS")
		)
		(fp_line
			(start 0.7874 -0.4064)
			(end 0.7874 0.4064)
			(stroke
				(width 0.1524)
				(type default)
			)
			(layer "F.SilkS")
		)
		(fp_line
			(start -0.7874 0.4064)
			(end -0.7874 -0.4064)
			(stroke
				(width 0.1524)
				(type default)
			)
			(layer "F.SilkS")
		)
		(fp_line
			(start -0.7874 -0.4064)
			(end 0.7874 -0.4064)
			(stroke
				(width 0.1524)
				(type default)
			)
			(layer "F.SilkS")
		)
		(fp_line
			(start 0.67945 0.3048)
			(end 0.120396 0.3048)
			(stroke
				(width 0.1)
				(type default)
			)
			(layer "F.Fab")
		)
		(fp_line
			(start 0.67945 -0.3048)
			(end 0.67945 0.3048)
			(stroke
				(width 0.1)
				(type default)
			)
			(layer "F.Fab")
		)
		(fp_line
			(start 0.12065 -0.2794)
			(end 0.12065 -0.3048)
			(stroke
				(width 0.1)
				(type default)
			)
			(layer "F.Fab")
		)
		(fp_line
			(start 0.12065 -0.3048)
			(end 0.67945 -0.3048)
			(stroke
				(width 0.1)
				(type default)
			)
			(layer "F.Fab")
		)
		(fp_line
			(start 0.120396 0.3048)
			(end 0.120396 0.2794)
			(stroke
				(width 0.1)
				(type default)
			)
			(layer "F.Fab")
		)
		(fp_line
			(start 0.120396 0.2794)
			(end -0.12065 0.2794)
			(stroke
				(width 0.1)
				(type default)
			)
			(layer "F.Fab")
		)
		(fp_line
			(start -0.12065 0.3048)
			(end -0.67945 0.3048)
			(stroke
				(width 0.1)
				(type default)
			)
			(layer "F.Fab")
		)
		(fp_line
			(start -0.12065 0.2794)
			(end -0.12065 0.3048)
			(stroke
				(width 0.1)
				(type default)
			)
			(layer "F.Fab")
		)
		(fp_line
			(start -0.12065 -0.2794)
			(end 0.12065 -0.2794)
			(stroke
				(width 0.1)
				(type default)
			)
			(layer "F.Fab")
		)
		(fp_line
			(start -0.12065 -0.305054)
			(end -0.12065 -0.2794)
			(stroke
				(width 0.1)
				(type default)
			)
			(layer "F.Fab")
		)
		(fp_line
			(start -0.67945 0.3048)
			(end -0.67945 -0.305054)
			(stroke
				(width 0.1)
				(type default)
			)
			(layer "F.Fab")
		)
		(fp_line
			(start -0.67945 -0.305054)
			(end -0.12065 -0.305054)
			(stroke
				(width 0.1)
				(type default)
			)
			(layer "F.Fab")
		)
		(pad "1" smd circle
			(at -0.40005 0 180)
			(size 0 0)
			(layers "F.Cu" "F.Mask" "F.Paste")
			(net "P3V3_AUX")
		)
		(pad "2" smd circle
			(at 0.40005 0 180)
			(size 0 0)
			(layers "F.Cu" "F.Mask" "F.Paste")
			(net "P12V_OCP_SFF_EN_R3")
		)
	)
	(footprint ""
		(layer "F.Cu")
		(at 55.753 -39.751)
		(property "Reference" "C1065"
			(at 0 0 0)
			(layer "F.SilkS")
			(hide yes)
			(effects
				(font
					(size 1.27 1.27)
				)
			)
		)
		(property "Value" ""
			(at 0 0 0)
			(layer "F.Fab")
			(effects
				(font
					(size 1.27 1.27)
				)
			)
		)
		(duplicate_pad_numbers_are_jumpers no)
		(fp_line
			(start -0.7874 -0.4064)
			(end 0.7874 -0.4064)
			(stroke
				(width 0.1524)
				(type default)
			)
			(layer "F.SilkS")
		)
		(fp_line
			(start -0.7874 0.4064)
			(end -0.7874 -0.4064)
			(stroke
				(width 0.1524)
				(type default)
			)
			(layer "F.SilkS")
		)
		(fp_line
			(start 0.7874 -0.4064)
			(end 0.7874 0.4064)
			(stroke
				(width 0.1524)
				(type default)
			)
			(layer "F.SilkS")
		)
		(fp_line
			(start 0.7874 0.4064)
			(end -0.7874 0.4064)
			(stroke
				(width 0.1524)
				(type default)
			)
			(layer "F.SilkS")
		)
		(fp_line
			(start -0.67945 -0.305054)
			(end -0.12065 -0.305054)
			(stroke
				(width 0.1)
				(type default)
			)
			(layer "F.Fab")
		)
		(fp_line
			(start -0.67945 0.3048)
			(end -0.67945 -0.305054)
			(stroke
				(width 0.1)
				(type default)
			)
			(layer "F.Fab")
		)
		(fp_line
			(start -0.12065 -0.305054)
			(end -0.12065 -0.2794)
			(stroke
				(width 0.1)
				(type default)
			)
			(layer "F.Fab")
		)
		(fp_line
			(start -0.12065 -0.2794)
			(end 0.12065 -0.2794)
			(stroke
				(width 0.1)
				(type default)
			)
			(layer "F.Fab")
		)
		(fp_line
			(start -0.12065 0.2794)
			(end -0.12065 0.3048)
			(stroke
				(width 0.1)
				(type default)
			)
			(layer "F.Fab")
		)
		(fp_line
			(start -0.12065 0.3048)
			(end -0.67945 0.3048)
			(stroke
				(width 0.1)
				(type default)
			)
			(layer "F.Fab")
		)
		(fp_line
			(start 0.120396 0.2794)
			(end -0.12065 0.2794)
			(stroke
				(width 0.1)
				(type default)
			)
			(layer "F.Fab")
		)
		(fp_line
			(start 0.120396 0.3048)
			(end 0.120396 0.2794)
			(stroke
				(width 0.1)
				(type default)
			)
			(layer "F.Fab")
		)
		(fp_line
			(start 0.12065 -0.3048)
			(end 0.67945 -0.3048)
			(stroke
				(width 0.1)
				(type default)
			)
			(layer "F.Fab")
		)
		(fp_line
			(start 0.12065 -0.2794)
			(end 0.12065 -0.3048)
			(stroke
				(width 0.1)
				(type default)
			)
			(layer "F.Fab")
		)
		(fp_line
			(start 0.67945 -0.3048)
			(end 0.67945 0.3048)
			(stroke
				(width 0.1)
				(type default)
			)
			(layer "F.Fab")
		)
		(fp_line
			(start 0.67945 0.3048)
			(end 0.120396 0.3048)
			(stroke
				(width 0.1)
				(type default)
			)
			(layer "F.Fab")
		)
		(pad "1" smd circle
			(at -0.40005 0)
			(size 0 0)
			(layers "F.Cu" "F.Mask" "F.Paste")
			(net "P3V3_AUX")
		)
		(pad "2" smd circle
			(at 0.40005 0)
			(size 0 0)
			(layers "F.Cu" "F.Mask" "F.Paste")
			(net "GND")
		)
	)
	(footprint ""
		(layer "F.Cu")
		(at 14.01826 -92.687648 -90)
		(property "Reference" "R3666"
			(at 0 0 270)
			(layer "F.SilkS")
			(hide yes)
			(effects
				(font
					(size 1.27 1.27)
				)
			)
		)
		(property "Value" ""
			(at 0 0 270)
			(layer "F.Fab")
			(effects
				(font
					(size 1.27 1.27)
				)
			)
		)
		(duplicate_pad_numbers_are_jumpers no)
		(fp_line
			(start -0.7874 0.4064)
			(end -0.7874 -0.4064)
			(stroke
				(width 0.1524)
				(type default)
			)
			(layer "F.SilkS")
		)
		(fp_line
			(start 0.7874 0.4064)
			(end -0.7874 0.4064)
			(stroke
				(width 0.1524)
				(type default)
			)
			(layer "F.SilkS")
		)
		(fp_line
			(start -0.7874 -0.4064)
			(end 0.7874 -0.4064)
			(stroke
				(width 0.1524)
				(type default)
			)
			(layer "F.SilkS")
		)
		(fp_line
			(start 0.7874 -0.4064)
			(end 0.7874 0.4064)
			(stroke
				(width 0.1524)
				(type default)
			)
			(layer "F.SilkS")
		)
		(fp_line
			(start -0.67945 0.3048)
			(end -0.67945 -0.305054)
			(stroke
				(width 0.1)
				(type default)
			)
			(layer "F.Fab")
		)
		(fp_line
			(start -0.12065 0.3048)
			(end -0.67945 0.3048)
			(stroke
				(width 0.1)
				(type default)
			)
			(layer "F.Fab")
		)
		(fp_line
			(start 0.120396 0.3048)
			(end 0.120396 0.2794)
			(stroke
				(width 0.1)
				(type default)
			)
			(layer "F.Fab")
		)
		(fp_line
			(start 0.67945 0.3048)
			(end 0.120396 0.3048)
			(stroke
				(width 0.1)
				(type default)
			)
			(layer "F.Fab")
		)
		(fp_line
			(start -0.12065 0.2794)
			(end -0.12065 0.3048)
			(stroke
				(width 0.1)
				(type default)
			)
			(layer "F.Fab")
		)
		(fp_line
			(start 0.120396 0.2794)
			(end -0.12065 0.2794)
			(stroke
				(width 0.1)
				(type default)
			)
			(layer "F.Fab")
		)
		(fp_line
			(start -0.12065 -0.2794)
			(end 0.12065 -0.2794)
			(stroke
				(width 0.1)
				(type default)
			)
			(layer "F.Fab")
		)
		(fp_line
			(start 0.12065 -0.2794)
			(end 0.12065 -0.3048)
			(stroke
				(width 0.1)
				(type default)
			)
			(layer "F.Fab")
		)
		(fp_line
			(start 0.12065 -0.3048)
			(end 0.67945 -0.3048)
			(stroke
				(width 0.1)
				(type default)
			)
			(layer "F.Fab")
		)
		(fp_line
			(start 0.67945 -0.3048)
			(end 0.67945 0.3048)
			(stroke
				(width 0.1)
				(type default)
			)
			(layer "F.Fab")
		)
		(fp_line
			(start -0.67945 -0.305054)
			(end -0.12065 -0.305054)
			(stroke
				(width 0.1)
				(type default)
			)
			(layer "F.Fab")
		)
		(fp_line
			(start -0.12065 -0.305054)
			(end -0.12065 -0.2794)
			(stroke
				(width 0.1)
				(type default)
			)
			(layer "F.Fab")
		)
		(pad "1" smd circle
			(at -0.40005 0 270)
			(size 0 0)
			(layers "F.Cu" "F.Mask" "F.Paste")
			(net "USB_HUB_TEST")
		)
		(pad "2" smd circle
			(at 0.40005 0 270)
			(size 0 0)
			(layers "F.Cu" "F.Mask" "F.Paste")
			(net "GND")
		)
	)
	(footprint ""
		(layer "F.Cu")
		(at 419.094666 -157.618684 -90)
		(property "Reference" "PR446"
			(at 0 0 270)
			(layer "F.SilkS")
			(hide yes)
			(effects
				(font
					(size 1.27 1.27)
				)
			)
		)
		(property "Value" ""
			(at 0 0 270)
			(layer "F.Fab")
			(effects
				(font
					(size 1.27 1.27)
				)
			)
		)
		(duplicate_pad_numbers_are_jumpers no)
		(fp_line
			(start -0.7874 0.4064)
			(end -0.7874 -0.4064)
			(stroke
				(width 0.1524)
				(type default)
			)
			(layer "F.SilkS")
		)
		(fp_line
			(start 0.7874 0.4064)
			(end -0.7874 0.4064)
			(stroke
				(width 0.1524)
				(type default)
			)
			(layer "F.SilkS")
		)
		(fp_line
			(start -0.7874 -0.4064)
			(end 0.7874 -0.4064)
			(stroke
				(width 0.1524)
				(type default)
			)
			(layer "F.SilkS")
		)
		(fp_line
			(start 0.7874 -0.4064)
			(end 0.7874 0.4064)
			(stroke
				(width 0.1524)
				(type default)
			)
			(layer "F.SilkS")
		)
		(fp_line
			(start -0.67945 0.3048)
			(end -0.67945 -0.305054)
			(stroke
				(width 0.1)
				(type default)
			)
			(layer "F.Fab")
		)
		(fp_line
			(start -0.12065 0.3048)
			(end -0.67945 0.3048)
			(stroke
				(width 0.1)
				(type default)
			)
			(layer "F.Fab")
		)
		(fp_line
			(start 0.120396 0.3048)
			(end 0.120396 0.2794)
			(stroke
				(width 0.1)
				(type default)
			)
			(layer "F.Fab")
		)
		(fp_line
			(start 0.67945 0.3048)
			(end 0.120396 0.3048)
			(stroke
				(width 0.1)
				(type default)
			)
			(layer "F.Fab")
		)
		(fp_line
			(start -0.12065 0.2794)
			(end -0.12065 0.3048)
			(stroke
				(width 0.1)
				(type default)
			)
			(layer "F.Fab")
		)
		(fp_line
			(start 0.120396 0.2794)
			(end -0.12065 0.2794)
			(stroke
				(width 0.1)
				(type default)
			)
			(layer "F.Fab")
		)
		(fp_line
			(start -0.12065 -0.2794)
			(end 0.12065 -0.2794)
			(stroke
				(width 0.1)
				(type default)
			)
			(layer "F.Fab")
		)
		(fp_line
			(start 0.12065 -0.2794)
			(end 0.12065 -0.3048)
			(stroke
				(width 0.1)
				(type default)
			)
			(layer "F.Fab")
		)
		(fp_line
			(start 0.12065 -0.3048)
			(end 0.67945 -0.3048)
			(stroke
				(width 0.1)
				(type default)
			)
			(layer "F.Fab")
		)
		(fp_line
			(start 0.67945 -0.3048)
			(end 0.67945 0.3048)
			(stroke
				(width 0.1)
				(type default)
			)
			(layer "F.Fab")
		)
		(fp_line
			(start -0.67945 -0.305054)
			(end -0.12065 -0.305054)
			(stroke
				(width 0.1)
				(type default)
			)
			(layer "F.Fab")
		)
		(fp_line
			(start -0.12065 -0.305054)
			(end -0.12065 -0.2794)
			(stroke
				(width 0.1)
				(type default)
			)
			(layer "F.Fab")
		)
		(pad "1" smd circle
			(at -0.40005 0 270)
			(size 0 0)
			(layers "F.Cu" "F.Mask" "F.Paste")
			(net "PVDDCR_CPU0_P0_PVCC")
		)
		(pad "2" smd circle
			(at 0.40005 0 270)
			(size 0 0)
			(layers "F.Cu" "F.Mask" "F.Paste")
			(net "P3V3_AUX")
		)
	)
)
